# T6G (Grand Teton) — schematic netlist excerpt (pin names and nets, part order shuffled) for the footprints in the layout excerpt that follows; sources: Cadence DE-HDL packaged netlist, KiCad conversion of 04192023_DAF0TMB3IC0_F0TG_MB_C_brd_V02_OCP.brd

R828  Q_RES  0 5% CHIP  pkg 0201LF  page 185 : A = SMB_RT_CPU0_P1_ROM_MUX_2D_R_SDA ; B = SMB_RT_CPU0_P1_ROM_MUX_2D_SDA
PC296_3  Q_CAP  22UF 16V 20% X6S  pkg C0805  page 212 : A = SW_P12V_AUX_PVDDCR_CPU0_P1_FLT ; B = GND
C2607  Q_CAP  22UF 4V 20% X6S  pkg C0402  page 70 : A = PVDD11_S3_P0 ; B = GND
R847  Q_RES  4.7K 5% CHIP  pkg 0201LF  page 185 : A = RT_ROM_SMB_MUX_ADDR0 ; B = GND

(kicad_pcb
	(version 20260206)
	(generator "pcbnew")
	(generator_version "10.0")
	(general
		(thickness 1.6)
		(legacy_teardrops no)
	)
	(paper "A4")
	(title_block
		(title "04192023_DAF0TMB3IC0_F0TG_MB_C_brd_V02_OCP.brd")
		(comment 1 "Grand Teton / footprints 5448-5451 of 8354")
	)
	(layers
		(0 "F.Cu" signal "TOP")
		(4 "In1.Cu" signal "GND")
		(6 "In2.Cu" signal "IN1")
		(8 "In3.Cu" signal "GND1")
		(10 "In4.Cu" signal "IN2")
		(12 "In5.Cu" signal "GND2")
		(14 "In6.Cu" signal "IN3")
		(16 "In7.Cu" signal "GND3")
		(18 "In8.Cu" signal "VCC")
		(20 "In9.Cu" signal "VCC1")
		(22 "In10.Cu" signal "GND4")
		(24 "In11.Cu" signal "IN4")
		(26 "In12.Cu" signal "GND5")
		(28 "In13.Cu" signal "IN5")
		(30 "In14.Cu" signal "GND6")
		(32 "In15.Cu" signal "IN6")
		(34 "In16.Cu" signal "GND7")
		(2 "B.Cu" signal "BOTTOM")
		(9 "F.Adhes" user "F.Adhesive")
		(11 "B.Adhes" user "B.Adhesive")
		(13 "F.Paste" user "Package Geometry/Pastemask Top")
		(15 "B.Paste" user "Package Geometry/Pastemask Bottom")
		(5 "F.SilkS" user "Ref Des/Silkscreen Top")
		(7 "B.SilkS" user "Ref Des/Silkscreen Bottom")
		(1 "F.Mask" user "Board Geometry/Soldermask Top")
		(3 "B.Mask" user "Board Geometry/Soldermask Bottom")
		(17 "Dwgs.User" user "User.Drawings")
		(19 "Cmts.User" user "User.Comments")
		(21 "Eco1.User" user "User.Eco1")
		(23 "Eco2.User" user "User.Eco2")
		(25 "Edge.Cuts" user "Board Geometry/Outline")
		(27 "Margin" user)
		(31 "F.CrtYd" user "Package Geometry/Place Bound Top")
		(29 "B.CrtYd" user "Package Geometry/Place Bound Bottom")
		(35 "F.Fab" user "Ref Des/Assembly Top")
		(33 "B.Fab" user "Ref Des/Assembly Bottom")
	)
	(footprint ""
		(layer "B.Cu")
		(at 356.311454 -264.35431)
		(property "Reference" "C2607"
			(at 0 0 0)
			(layer "B.SilkS")
			(hide yes)
			(effects
				(font
					(size 1.27 1.27)
				)
				(justify mirror)
			)
		)
		(property "Value" ""
			(at 0 0 0)
			(layer "B.Fab")
			(effects
				(font
					(size 1.27 1.27)
				)
				(justify mirror)
			)
		)
		(duplicate_pad_numbers_are_jumpers no)
		(fp_line
			(start -0.7874 -0.4064)
			(end -0.7874 0.4064)
			(stroke
				(width 0.1524)
				(type default)
			)
			(layer "B.SilkS")
		)
		(fp_line
			(start -0.7874 0.4064)
			(end 0.7874 0.4064)
			(stroke
				(width 0.1524)
				(type default)
			)
			(layer "B.SilkS")
		)
		(fp_line
			(start 0.7874 -0.4064)
			(end -0.7874 -0.4064)
			(stroke
				(width 0.1524)
				(type default)
			)
			(layer "B.SilkS")
		)
		(fp_line
			(start 0.7874 0.4064)
			(end 0.7874 -0.4064)
			(stroke
				(width 0.1524)
				(type default)
			)
			(layer "B.SilkS")
		)
		(fp_line
			(start -0.67945 -0.3048)
			(end -0.67945 0.3048)
			(stroke
				(width 0.1)
				(type default)
			)
			(layer "B.Fab")
		)
		(fp_line
			(start -0.67945 0.3048)
			(end -0.120396 0.3048)
			(stroke
				(width 0.1)
				(type default)
			)
			(layer "B.Fab")
		)
		(fp_line
			(start -0.12065 -0.3048)
			(end -0.67945 -0.3048)
			(stroke
				(width 0.1)
				(type default)
			)
			(layer "B.Fab")
		)
		(fp_line
			(start -0.12065 -0.2794)
			(end -0.12065 -0.3048)
			(stroke
				(width 0.1)
				(type default)
			)
			(layer "B.Fab")
		)
		(fp_line
			(start -0.120396 0.2794)
			(end 0.12065 0.2794)
			(stroke
				(width 0.1)
				(type default)
			)
			(layer "B.Fab")
		)
		(fp_line
			(start -0.120396 0.3048)
			(end -0.120396 0.2794)
			(stroke
				(width 0.1)
				(type default)
			)
			(layer "B.Fab")
		)
		(fp_line
			(start 0.12065 -0.305054)
			(end 0.12065 -0.2794)
			(stroke
				(width 0.1)
				(type default)
			)
			(layer "B.Fab")
		)
		(fp_line
			(start 0.12065 -0.2794)
			(end -0.12065 -0.2794)
			(stroke
				(width 0.1)
				(type default)
			)
			(layer "B.Fab")
		)
		(fp_line
			(start 0.12065 0.2794)
			(end 0.12065 0.3048)
			(stroke
				(width 0.1)
				(type default)
			)
			(layer "B.Fab")
		)
		(fp_line
			(start 0.12065 0.3048)
			(end 0.67945 0.3048)
			(stroke
				(width 0.1)
				(type default)
			)
			(layer "B.Fab")
		)
		(fp_line
			(start 0.67945 -0.305054)
			(end 0.12065 -0.305054)
			(stroke
				(width 0.1)
				(type default)
			)
			(layer "B.Fab")
		)
		(fp_line
			(start 0.67945 0.3048)
			(end 0.67945 -0.305054)
			(stroke
				(width 0.1)
				(type default)
			)
			(layer "B.Fab")
		)
		(pad "1" smd circle
			(at 0.40005 0 180)
			(size 0 0)
			(layers "B.Cu" "B.Mask" "B.Paste")
			(net "PVDD11_S3_P0")
		)
		(pad "2" smd circle
			(at -0.40005 0 180)
			(size 0 0)
			(layers "B.Cu" "B.Mask" "B.Paste")
			(net "GND")
		)
	)
	(footprint ""
		(layer "B.Cu")
		(at 97.996248 -182.555134 -90)
		(property "Reference" "PC296_3"
			(at 0 0 90)
			(layer "B.SilkS")
			(hide yes)
			(effects
				(font
					(size 1.27 1.27)
				)
				(justify mirror)
			)
		)
		(property "Value" ""
			(at 0 0 90)
			(layer "B.Fab")
			(effects
				(font
					(size 1.27 1.27)
				)
				(justify mirror)
			)
		)
		(duplicate_pad_numbers_are_jumpers no)
		(fp_line
			(start -1.524 0.762)
			(end 1.524 0.762)
			(stroke
				(width 0.1524)
				(type default)
			)
			(layer "B.SilkS")
		)
		(fp_line
			(start 1.524 0.762)
			(end 1.524 -0.762)
			(stroke
				(width 0.1524)
				(type default)
			)
			(layer "B.SilkS")
		)
		(fp_line
			(start -1.524 -0.762)
			(end -1.524 0.762)
			(stroke
				(width 0.1524)
				(type default)
			)
			(layer "B.SilkS")
		)
		(fp_line
			(start 1.524 -0.762)
			(end -1.524 -0.762)
			(stroke
				(width 0.1524)
				(type default)
			)
			(layer "B.SilkS")
		)
		(fp_line
			(start -1.1049 0.724916)
			(end -1.1049 -0.724916)
			(stroke
				(width 0.1)
				(type default)
			)
			(layer "B.Fab")
		)
		(fp_line
			(start 1.1049 0.724916)
			(end -1.1049 0.724916)
			(stroke
				(width 0.1)
				(type default)
			)
			(layer "B.Fab")
		)
		(fp_line
			(start -1.1049 -0.724916)
			(end 1.1049 -0.724916)
			(stroke
				(width 0.1)
				(type default)
			)
			(layer "B.Fab")
		)
		(fp_line
			(start 1.1049 -0.724916)
			(end 1.1049 0.724916)
			(stroke
				(width 0.1)
				(type default)
			)
			(layer "B.Fab")
		)
		(pad "1" smd rect
			(at 0.889 0 270)
			(size 1.016 1.27)
			(layers "B.Cu" "B.Mask" "B.Paste")
			(net "SW_P12V_AUX_PVDDCR_CPU0_P1_FLT")
		)
		(pad "2" smd rect
			(at -0.889 0 270)
			(size 1.016 1.27)
			(layers "B.Cu" "B.Mask" "B.Paste")
			(net "GND")
		)
	)
	(footprint ""
		(layer "B.Cu")
		(at 255.905 -339.63864 180)
		(property "Reference" "R828"
			(at 0 0 0)
			(layer "B.SilkS")
			(hide yes)
			(effects
				(font
					(size 1.27 1.27)
				)
				(justify mirror)
			)
		)
		(property "Value" ""
			(at 0 0 0)
			(layer "B.Fab")
			(effects
				(font
					(size 1.27 1.27)
				)
				(justify mirror)
			)
		)
		(duplicate_pad_numbers_are_jumpers no)
		(fp_line
			(start 0.32512 0.175006)
			(end 0.32512 -0.175006)
			(stroke
				(width 0.1)
				(type default)
			)
			(layer "B.Fab")
		)
		(fp_line
			(start 0.32512 -0.175006)
			(end -0.32512 -0.175006)
			(stroke
				(width 0.1)
				(type default)
			)
			(layer "B.Fab")
		)
		(fp_line
			(start -0.32512 0.175006)
			(end 0.32512 0.175006)
			(stroke
				(width 0.1)
				(type default)
			)
			(layer "B.Fab")
		)
		(fp_line
			(start -0.32512 -0.175006)
			(end -0.32512 0.175006)
			(stroke
				(width 0.1)
				(type default)
			)
			(layer "B.Fab")
		)
		(pad "1" smd rect
			(at 0.2667 0)
			(size 0.3048 0.381)
			(layers "B.Cu" "B.Mask" "B.Paste")
			(net "SMB_RT_CPU0_P1_ROM_MUX_2D_R_SDA")
		)
		(pad "2" smd rect
			(at -0.2667 0 180)
			(size 0.3048 0.381)
			(layers "B.Cu" "B.Mask" "B.Paste")
			(net "SMB_RT_CPU0_P1_ROM_MUX_2D_SDA")
		)
	)
	(footprint ""
		(layer "B.Cu")
		(at 239.141 -330.581)
		(property "Reference" "R847"
			(at 0 0 0)
			(layer "B.SilkS")
			(hide yes)
			(effects
				(font
					(size 1.27 1.27)
				)
				(justify mirror)
			)
		)
		(property "Value" ""
			(at 0 0 0)
			(layer "B.Fab")
			(effects
				(font
					(size 1.27 1.27)
				)
				(justify mirror)
			)
		)
		(duplicate_pad_numbers_are_jumpers no)
		(fp_line
			(start -0.32512 -0.175006)
			(end -0.32512 0.175006)
			(stroke
				(width 0.1)
				(type default)
			)
			(layer "B.Fab")
		)
		(fp_line
			(start -0.32512 0.175006)
			(end 0.32512 0.175006)
			(stroke
				(width 0.1)
				(type default)
			)
			(layer "B.Fab")
		)
		(fp_line
			(start 0.32512 -0.175006)
			(end -0.32512 -0.175006)
			(stroke
				(width 0.1)
				(type default)
			)
			(layer "B.Fab")
		)
		(fp_line
			(start 0.32512 0.175006)
			(end 0.32512 -0.175006)
			(stroke
				(width 0.1)
				(type default)
			)
			(layer "B.Fab")
		)
		(pad "1" smd rect
			(at 0.2667 0 180)
			(size 0.3048 0.381)
			(layers "B.Cu" "B.Mask" "B.Paste")
			(net "RT_ROM_SMB_MUX_ADDR0")
		)
		(pad "2" smd rect
			(at -0.2667 0)
			(size 0.3048 0.381)
			(layers "B.Cu" "B.Mask" "B.Paste")
			(net "GND")
		)
	)
)
